(kicad_pcb
	(version 20260206)
	(generator "pcbnew")
	(generator_version "10.0")
	(general
		(thickness 1.6)
		(legacy_teardrops no)
	)
	(paper "A4")
	(title_block
		(title "03242023_DA0F0TMBIJ0_F0T_Motherboard_J_brd_V01_OCP.brd")
		(comment 1 "Grand Teton / footprints 1473-1478 of 6105")
	)
	(layers
		(0 "F.Cu" signal "TOP")
		(4 "In1.Cu" signal "GND")
		(6 "In2.Cu" signal "IN1")
		(8 "In3.Cu" signal "GND1")
		(10 "In4.Cu" signal "IN2")
		(12 "In5.Cu" signal "GND2")
		(14 "In6.Cu" signal "IN3")
		(16 "In7.Cu" signal "GND3")
		(18 "In8.Cu" signal "VCC")
		(20 "In9.Cu" signal "VCC1")
		(22 "In10.Cu" signal "GND4")
		(24 "In11.Cu" signal "IN4")
		(26 "In12.Cu" signal "GND5")
		(28 "In13.Cu" signal "IN5")
		(30 "In14.Cu" signal "GND6")
		(32 "In15.Cu" signal "IN6")
		(34 "In16.Cu" signal "GND7")
		(2 "B.Cu" signal "BOTTOM")
		(9 "F.Adhes" user "F.Adhesive")
		(11 "B.Adhes" user "B.Adhesive")
		(13 "F.Paste" user "Package Geometry/Pastemask Top")
		(15 "B.Paste" user "Package Geometry/Pastemask Bottom")
		(5 "F.SilkS" user "Ref Des/Silkscreen Top")
		(7 "B.SilkS" user "Ref Des/Silkscreen Bottom")
		(1 "F.Mask" user "Board Geometry/Soldermask Top")
		(3 "B.Mask" user "Board Geometry/Soldermask Bottom")
		(17 "Dwgs.User" user "User.Drawings")
		(19 "Cmts.User" user "User.Comments")
		(21 "Eco1.User" user "User.Eco1")
		(23 "Eco2.User" user "User.Eco2")
		(25 "Edge.Cuts" user "Board Geometry/Outline")
		(27 "Margin" user)
		(31 "F.CrtYd" user "Package Geometry/Place Bound Top")
		(29 "B.CrtYd" user "Package Geometry/Place Bound Bottom")
		(35 "F.Fab" user "Ref Des/Assembly Top")
		(33 "B.Fab" user "Ref Des/Assembly Bottom")
	)
	(footprint ""
		(layer "F.Cu")
		(at 452.486522 -76.007722)
		(property "Reference" "PR836"
			(at 0 0 0)
			(layer "F.SilkS")
			(hide yes)
			(effects
				(font
					(size 1.27 1.27)
				)
			)
		)
		(property "Value" ""
			(at 0 0 0)
			(layer "F.Fab")
			(effects
				(font
					(size 1.27 1.27)
				)
			)
		)
		(duplicate_pad_numbers_are_jumpers no)
		(fp_line
			(start -0.7874 -0.4064)
			(end 0.7874 -0.4064)
			(stroke
				(width 0.1524)
				(type default)
			)
			(layer "F.SilkS")
		)
		(fp_line
			(start -0.7874 0.4064)
			(end -0.7874 -0.4064)
			(stroke
				(width 0.1524)
				(type default)
			)
			(layer "F.SilkS")
		)
		(fp_line
			(start 0.7874 -0.4064)
			(end 0.7874 0.4064)
			(stroke
				(width 0.1524)
				(type default)
			)
			(layer "F.SilkS")
		)
		(fp_line
			(start 0.7874 0.4064)
			(end -0.7874 0.4064)
			(stroke
				(width 0.1524)
				(type default)
			)
			(layer "F.SilkS")
		)
		(fp_line
			(start -0.67945 -0.305054)
			(end -0.12065 -0.305054)
			(stroke
				(width 0.1)
				(type default)
			)
			(layer "F.Fab")
		)
		(fp_line
			(start -0.67945 0.3048)
			(end -0.67945 -0.305054)
			(stroke
				(width 0.1)
				(type default)
			)
			(layer "F.Fab")
		)
		(fp_line
			(start -0.12065 -0.305054)
			(end -0.12065 -0.2794)
			(stroke
				(width 0.1)
				(type default)
			)
			(layer "F.Fab")
		)
		(fp_line
			(start -0.12065 -0.2794)
			(end 0.12065 -0.2794)
			(stroke
				(width 0.1)
				(type default)
			)
			(layer "F.Fab")
		)
		(fp_line
			(start -0.12065 0.2794)
			(end -0.12065 0.3048)
			(stroke
				(width 0.1)
				(type default)
			)
			(layer "F.Fab")
		)
		(fp_line
			(start -0.12065 0.3048)
			(end -0.67945 0.3048)
			(stroke
				(width 0.1)
				(type default)
			)
			(layer "F.Fab")
		)
		(fp_line
			(start 0.120396 0.2794)
			(end -0.12065 0.2794)
			(stroke
				(width 0.1)
				(type default)
			)
			(layer "F.Fab")
		)
		(fp_line
			(start 0.120396 0.3048)
			(end 0.120396 0.2794)
			(stroke
				(width 0.1)
				(type default)
			)
			(layer "F.Fab")
		)
		(fp_line
			(start 0.12065 -0.3048)
			(end 0.67945 -0.3048)
			(stroke
				(width 0.1)
				(type default)
			)
			(layer "F.Fab")
		)
		(fp_line
			(start 0.12065 -0.2794)
			(end 0.12065 -0.3048)
			(stroke
				(width 0.1)
				(type default)
			)
			(layer "F.Fab")
		)
		(fp_line
			(start 0.67945 -0.3048)
			(end 0.67945 0.3048)
			(stroke
				(width 0.1)
				(type default)
			)
			(layer "F.Fab")
		)
		(fp_line
			(start 0.67945 0.3048)
			(end 0.120396 0.3048)
			(stroke
				(width 0.1)
				(type default)
			)
			(layer "F.Fab")
		)
		(pad "1" smd circle
			(at -0.40005 0)
			(size 0 0)
			(layers "F.Cu" "F.Mask" "F.Paste")
			(net "P3V3_AUX_VOS")
		)
		(pad "2" smd circle
			(at 0.40005 0)
			(size 0 0)
			(layers "F.Cu" "F.Mask" "F.Paste")
			(net "P3V3_AUX")
		)
	)
	(footprint ""
		(layer "F.Cu")
		(at 130.10388 -21.554948 90)
		(property "Reference" "R3302"
			(at 0 0 90)
			(layer "F.SilkS")
			(hide yes)
			(effects
				(font
					(size 1.27 1.27)
				)
			)
		)
		(property "Value" ""
			(at 0 0 90)
			(layer "F.Fab")
			(effects
				(font
					(size 1.27 1.27)
				)
			)
		)
		(duplicate_pad_numbers_are_jumpers no)
		(fp_line
			(start 0.7874 -0.4064)
			(end 0.7874 0.4064)
			(stroke
				(width 0.1524)
				(type default)
			)
			(layer "F.SilkS")
		)
		(fp_line
			(start -0.7874 -0.4064)
			(end 0.7874 -0.4064)
			(stroke
				(width 0.1524)
				(type default)
			)
			(layer "F.SilkS")
		)
		(fp_line
			(start 0.7874 0.4064)
			(end -0.7874 0.4064)
			(stroke
				(width 0.1524)
				(type default)
			)
			(layer "F.SilkS")
		)
		(fp_line
			(start -0.7874 0.4064)
			(end -0.7874 -0.4064)
			(stroke
				(width 0.1524)
				(type default)
			)
			(layer "F.SilkS")
		)
		(fp_line
			(start -0.12065 -0.305054)
			(end -0.12065 -0.2794)
			(stroke
				(width 0.1)
				(type default)
			)
			(layer "F.Fab")
		)
		(fp_line
			(start -0.67945 -0.305054)
			(end -0.12065 -0.305054)
			(stroke
				(width 0.1)
				(type default)
			)
			(layer "F.Fab")
		)
		(fp_line
			(start 0.67945 -0.3048)
			(end 0.67945 0.3048)
			(stroke
				(width 0.1)
				(type default)
			)
			(layer "F.Fab")
		)
		(fp_line
			(start 0.12065 -0.3048)
			(end 0.67945 -0.3048)
			(stroke
				(width 0.1)
				(type default)
			)
			(layer "F.Fab")
		)
		(fp_line
			(start 0.12065 -0.2794)
			(end 0.12065 -0.3048)
			(stroke
				(width 0.1)
				(type default)
			)
			(layer "F.Fab")
		)
		(fp_line
			(start -0.12065 -0.2794)
			(end 0.12065 -0.2794)
			(stroke
				(width 0.1)
				(type default)
			)
			(layer "F.Fab")
		)
		(fp_line
			(start 0.120396 0.2794)
			(end -0.12065 0.2794)
			(stroke
				(width 0.1)
				(type default)
			)
			(layer "F.Fab")
		)
		(fp_line
			(start -0.12065 0.2794)
			(end -0.12065 0.3048)
			(stroke
				(width 0.1)
				(type default)
			)
			(layer "F.Fab")
		)
		(fp_line
			(start 0.67945 0.3048)
			(end 0.120396 0.3048)
			(stroke
				(width 0.1)
				(type default)
			)
			(layer "F.Fab")
		)
		(fp_line
			(start 0.120396 0.3048)
			(end 0.120396 0.2794)
			(stroke
				(width 0.1)
				(type default)
			)
			(layer "F.Fab")
		)
		(fp_line
			(start -0.12065 0.3048)
			(end -0.67945 0.3048)
			(stroke
				(width 0.1)
				(type default)
			)
			(layer "F.Fab")
		)
		(fp_line
			(start -0.67945 0.3048)
			(end -0.67945 -0.305054)
			(stroke
				(width 0.1)
				(type default)
			)
			(layer "F.Fab")
		)
		(pad "1" smd circle
			(at -0.40005 0 90)
			(size 0 0)
			(layers "F.Cu" "F.Mask" "F.Paste")
			(net "TP_PCIE_HPM_TXN<3>")
		)
		(pad "2" smd circle
			(at 0.40005 0 90)
			(size 0 0)
			(layers "F.Cu" "F.Mask" "F.Paste")
			(net "FM_PCH_SPKR")
		)
	)
	(footprint ""
		(layer "F.Cu")
		(at 437.58358 -55.26532)
		(property "Reference" "Q56"
			(at -0.813308 3.743452 0)
			(unlocked yes)
			(layer "F.SilkS")
			(effects
				(font
					(size 0.7874 0.5842)
					(thickness 0.1524)
				)
			)
		)
		(property "Value" ""
			(at 0 0 0)
			(layer "F.Fab")
			(effects
				(font
					(size 1.27 1.27)
				)
			)
		)
		(duplicate_pad_numbers_are_jumpers no)
		(fp_line
			(start -2.350008 -2.649982)
			(end 2.350008 -2.649982)
			(stroke
				(width 0.1524)
				(type default)
			)
			(layer "F.SilkS")
		)
		(fp_line
			(start -2.350008 -2.4384)
			(end -2.350008 -2.649982)
			(stroke
				(width 0.1524)
				(type default)
			)
			(layer "F.SilkS")
		)
		(fp_line
			(start -2.350008 2.649982)
			(end -2.350008 2.413)
			(stroke
				(width 0.1524)
				(type default)
			)
			(layer "F.SilkS")
		)
		(fp_line
			(start 2.350008 -2.649982)
			(end 2.350008 -2.4892)
			(stroke
				(width 0.1524)
				(type default)
			)
			(layer "F.SilkS")
		)
		(fp_line
			(start 2.350008 2.4892)
			(end 2.350008 2.649982)
			(stroke
				(width 0.1524)
				(type default)
			)
			(layer "F.SilkS")
		)
		(fp_line
			(start 2.350008 2.649982)
			(end -2.350008 2.649982)
			(stroke
				(width 0.1524)
				(type default)
			)
			(layer "F.SilkS")
		)
		(fp_poly
			(pts
				(xy -3.00609 -2.66827) (xy -3.38709 -3.70967) (xy -2.58699 -3.70967)
			)
			(stroke
				(width 0)
				(type default)
			)
			(fill yes)
			(layer "F.SilkS")
		)
		(fp_line
			(start -2.350008 -2.649982)
			(end 2.350008 -2.649982)
			(stroke
				(width 0.1)
				(type default)
			)
			(layer "F.Fab")
		)
		(fp_line
			(start -2.350008 2.649982)
			(end -2.350008 -2.649982)
			(stroke
				(width 0.1)
				(type default)
			)
			(layer "F.Fab")
		)
		(fp_line
			(start 2.350008 -2.649982)
			(end 2.350008 2.649982)
			(stroke
				(width 0.1)
				(type default)
			)
			(layer "F.Fab")
		)
		(fp_line
			(start 2.350008 2.649982)
			(end -2.350008 2.649982)
			(stroke
				(width 0.1)
				(type default)
			)
			(layer "F.Fab")
		)
		(fp_poly
			(pts
				(xy -3.717544 -1.905) (xy -4.758944 -2.3241) (xy -4.758944 -1.524)
			)
			(stroke
				(width 0)
				(type default)
			)
			(fill yes)
			(layer "F.Fab")
		)
		(pad "1" smd rect
			(at -2.999994 -1.905 270)
			(size 0.7112 1.1684)
			(layers "F.Cu" "F.Mask" "F.Paste")
			(net "P3V3")
		)
		(pad "2" smd rect
			(at -2.999994 -0.635 270)
			(size 0.7112 1.1684)
			(layers "F.Cu" "F.Mask" "F.Paste")
			(net "P3V3")
		)
		(pad "3" smd rect
			(at -2.999994 0.635 270)
			(size 0.7112 1.1684)
			(layers "F.Cu" "F.Mask" "F.Paste")
			(net "P3V3")
		)
		(pad "4" smd rect
			(at -2.999994 1.905 270)
			(size 0.7112 1.1684)
			(layers "F.Cu" "F.Mask" "F.Paste")
			(net "PWRGD_P5V_ISO_R")
		)
		(pad "5" smd circle
			(at 0.925068 0 270)
			(size 0 0)
			(layers "F.Cu" "F.Mask" "F.Paste")
			(net "P3V3_AUX")
		)
		(zone
			(layer "F.Cu")
			(hatch none 0.5)
			(connect_pads
				(clearance 0)
			)
			(min_thickness 0.25)
			(keepout
				(tracks not_allowed)
				(vias allowed)
				(pads allowed)
				(copperpour not_allowed)
				(footprints allowed)
			)
			(placement
				(enabled no)
				(sheetname "")
			)
			(fill
				(thermal_gap 0.5)
				(thermal_bridge_width 0.5)
				(island_removal_mode 0)
			)
			(polygon
				(pts
					(xy 436.13578 -57.42432) (xy 436.13578 -53.10632) (xy 436.13578 -52.62372) (xy 435.23408 -52.62372)
					(xy 435.23408 -57.90692) (xy 435.873652 -57.90692) (xy 436.13578 -57.644792)
				)
			)
		)
	)
	(footprint ""
		(layer "F.Cu")
		(at 190.41364 -67.391788 180)
		(property "Reference" "PR3945"
			(at 0 0 180)
			(layer "F.SilkS")
			(hide yes)
			(effects
				(font
					(size 1.27 1.27)
				)
			)
		)
		(property "Value" ""
			(at 0 0 180)
			(layer "F.Fab")
			(effects
				(font
					(size 1.27 1.27)
				)
			)
		)
		(duplicate_pad_numbers_are_jumpers no)
		(fp_line
			(start 0.7874 0.4064)
			(end -0.7874 0.4064)
			(stroke
				(width 0.1524)
				(type default)
			)
			(layer "F.SilkS")
		)
		(fp_line
			(start 0.7874 -0.4064)
			(end 0.7874 0.4064)
			(stroke
				(width 0.1524)
				(type default)
			)
			(layer "F.SilkS")
		)
		(fp_line
			(start -0.7874 0.4064)
			(end -0.7874 -0.4064)
			(stroke
				(width 0.1524)
				(type default)
			)
			(layer "F.SilkS")
		)
		(fp_line
			(start -0.7874 -0.4064)
			(end 0.7874 -0.4064)
			(stroke
				(width 0.1524)
				(type default)
			)
			(layer "F.SilkS")
		)
		(fp_line
			(start 0.67945 0.3048)
			(end 0.120396 0.3048)
			(stroke
				(width 0.1)
				(type default)
			)
			(layer "F.Fab")
		)
		(fp_line
			(start 0.67945 -0.3048)
			(end 0.67945 0.3048)
			(stroke
				(width 0.1)
				(type default)
			)
			(layer "F.Fab")
		)
		(fp_line
			(start 0.12065 -0.2794)
			(end 0.12065 -0.3048)
			(stroke
				(width 0.1)
				(type default)
			)
			(layer "F.Fab")
		)
		(fp_line
			(start 0.12065 -0.3048)
			(end 0.67945 -0.3048)
			(stroke
				(width 0.1)
				(type default)
			)
			(layer "F.Fab")
		)
		(fp_line
			(start 0.120396 0.3048)
			(end 0.120396 0.2794)
			(stroke
				(width 0.1)
				(type default)
			)
			(layer "F.Fab")
		)
		(fp_line
			(start 0.120396 0.2794)
			(end -0.12065 0.2794)
			(stroke
				(width 0.1)
				(type default)
			)
			(layer "F.Fab")
		)
		(fp_line
			(start -0.12065 0.3048)
			(end -0.67945 0.3048)
			(stroke
				(width 0.1)
				(type default)
			)
			(layer "F.Fab")
		)
		(fp_line
			(start -0.12065 0.2794)
			(end -0.12065 0.3048)
			(stroke
				(width 0.1)
				(type default)
			)
			(layer "F.Fab")
		)
		(fp_line
			(start -0.12065 -0.2794)
			(end 0.12065 -0.2794)
			(stroke
				(width 0.1)
				(type default)
			)
			(layer "F.Fab")
		)
		(fp_line
			(start -0.12065 -0.305054)
			(end -0.12065 -0.2794)
			(stroke
				(width 0.1)
				(type default)
			)
			(layer "F.Fab")
		)
		(fp_line
			(start -0.67945 0.3048)
			(end -0.67945 -0.305054)
			(stroke
				(width 0.1)
				(type default)
			)
			(layer "F.Fab")
		)
		(fp_line
			(start -0.67945 -0.305054)
			(end -0.12065 -0.305054)
			(stroke
				(width 0.1)
				(type default)
			)
			(layer "F.Fab")
		)
		(pad "1" smd circle
			(at -0.40005 0 180)
			(size 0 0)
			(layers "F.Cu" "F.Mask" "F.Paste")
			(net "P3V3_E1S_MODE_0")
		)
		(pad "2" smd circle
			(at 0.40005 0 180)
			(size 0 0)
			(layers "F.Cu" "F.Mask" "F.Paste")
			(net "GND")
		)
	)
	(footprint ""
		(layer "F.Cu")
		(at 43.754294 -16.099536 90)
		(property "Reference" "C827"
			(at 0 0 90)
			(layer "F.SilkS")
			(hide yes)
			(effects
				(font
					(size 1.27 1.27)
				)
			)
		)
		(property "Value" ""
			(at 0 0 90)
			(layer "F.Fab")
			(effects
				(font
					(size 1.27 1.27)
				)
			)
		)
		(duplicate_pad_numbers_are_jumpers no)
		(fp_line
			(start 0.299974 -0.150114)
			(end 0.299974 0.150114)
			(stroke
				(width 0.1)
				(type default)
			)
			(layer "F.Fab")
		)
		(fp_line
			(start -0.299974 -0.150114)
			(end 0.299974 -0.150114)
			(stroke
				(width 0.1)
				(type default)
			)
			(layer "F.Fab")
		)
		(fp_line
			(start 0.299974 0.150114)
			(end -0.299974 0.150114)
			(stroke
				(width 0.1)
				(type default)
			)
			(layer "F.Fab")
		)
		(fp_line
			(start -0.299974 0.150114)
			(end -0.299974 -0.150114)
			(stroke
				(width 0.1)
				(type default)
			)
			(layer "F.Fab")
		)
		(pad "1" smd rect
			(at -0.2667 0 90)
			(size 0.3048 0.381)
			(layers "F.Cu" "F.Mask" "F.Paste")
			(net "P5E_CPU1_PE1_TX_C_DP<5>")
		)
		(pad "2" smd rect
			(at 0.2667 0 90)
			(size 0.3048 0.381)
			(layers "F.Cu" "F.Mask" "F.Paste")
			(net "P5E_CPU1_PE1_TX_DP<5>")
		)
	)
	(footprint ""
		(layer "F.Cu")
		(at 118.542816 -245.634256 -90)
		(property "Reference" "C264"
			(at 0 0 270)
			(layer "F.SilkS")
			(hide yes)
			(effects
				(font
					(size 1.27 1.27)
				)
			)
		)
		(property "Value" ""
			(at 0 0 270)
			(layer "F.Fab")
			(effects
				(font
					(size 1.27 1.27)
				)
			)
		)
		(duplicate_pad_numbers_are_jumpers no)
		(fp_line
			(start -0.7874 0.4064)
			(end -0.7874 -0.4064)
			(stroke
				(width 0.1524)
				(type default)
			)
			(layer "F.SilkS")
		)
		(fp_line
			(start 0.7874 0.4064)
			(end -0.7874 0.4064)
			(stroke
				(width 0.1524)
				(type default)
			)
			(layer "F.SilkS")
		)
		(fp_line
			(start -0.7874 -0.4064)
			(end 0.7874 -0.4064)
			(stroke
				(width 0.1524)
				(type default)
			)
			(layer "F.SilkS")
		)
		(fp_line
			(start 0.7874 -0.4064)
			(end 0.7874 0.4064)
			(stroke
				(width 0.1524)
				(type default)
			)
			(layer "F.SilkS")
		)
		(fp_line
			(start -0.67945 0.3048)
			(end -0.67945 -0.305054)
			(stroke
				(width 0.1)
				(type default)
			)
			(layer "F.Fab")
		)
		(fp_line
			(start -0.12065 0.3048)
			(end -0.67945 0.3048)
			(stroke
				(width 0.1)
				(type default)
			)
			(layer "F.Fab")
		)
		(fp_line
			(start 0.120396 0.3048)
			(end 0.120396 0.2794)
			(stroke
				(width 0.1)
				(type default)
			)
			(layer "F.Fab")
		)
		(fp_line
			(start 0.67945 0.3048)
			(end 0.120396 0.3048)
			(stroke
				(width 0.1)
				(type default)
			)
			(layer "F.Fab")
		)
		(fp_line
			(start -0.12065 0.2794)
			(end -0.12065 0.3048)
			(stroke
				(width 0.1)
				(type default)
			)
			(layer "F.Fab")
		)
		(fp_line
			(start 0.120396 0.2794)
			(end -0.12065 0.2794)
			(stroke
				(width 0.1)
				(type default)
			)
			(layer "F.Fab")
		)
		(fp_line
			(start -0.12065 -0.2794)
			(end 0.12065 -0.2794)
			(stroke
				(width 0.1)
				(type default)
			)
			(layer "F.Fab")
		)
		(fp_line
			(start 0.12065 -0.2794)
			(end 0.12065 -0.3048)
			(stroke
				(width 0.1)
				(type default)
			)
			(layer "F.Fab")
		)
		(fp_line
			(start 0.12065 -0.3048)
			(end 0.67945 -0.3048)
			(stroke
				(width 0.1)
				(type default)
			)
			(layer "F.Fab")
		)
		(fp_line
			(start 0.67945 -0.3048)
			(end 0.67945 0.3048)
			(stroke
				(width 0.1)
				(type default)
			)
			(layer "F.Fab")
		)
		(fp_line
			(start -0.67945 -0.305054)
			(end -0.12065 -0.305054)
			(stroke
				(width 0.1)
				(type default)
			)
			(layer "F.Fab")
		)
		(fp_line
			(start -0.12065 -0.305054)
			(end -0.12065 -0.2794)
			(stroke
				(width 0.1)
				(type default)
			)
			(layer "F.Fab")
		)
		(pad "1" smd circle
			(at -0.40005 0 270)
			(size 0 0)
			(layers "F.Cu" "F.Mask" "F.Paste")
			(net "PVCCIN_CPU1")
		)
		(pad "2" smd circle
			(at 0.40005 0 270)
			(size 0 0)
			(layers "F.Cu" "F.Mask" "F.Paste")
			(net "GND")
		)
	)
)
